# T6G (Grand Teton) — schematic netlist excerpt (pin names and nets, part order shuffled) for the footprints in the layout excerpt that follows; sources: Cadence DE-HDL packaged netlist, KiCad conversion of 04192023_DAF0TMB3IC0_F0TG_MB_C_brd_V02_OCP.brd

R4063  Q_RES  0 5% CHIP  pkg 0402LF  page 146 : A = E1S_0_P3V3_EN ; B = P3V3_E1S_EN_0_R
C1561  Q_CAP  0.1UF 25V 10% EMPTY  pkg 0402  page 268 : A = U206_VS ; B = GND
R752  Q_RES  10K 1% CHIP  pkg 0201LF  page 331 : A = RST_RT_CPU1_P1_RESET_R_N ; B = GND

(kicad_pcb
	(version 20260206)
	(generator "pcbnew")
	(generator_version "10.0")
	(general
		(thickness 1.6)
		(legacy_teardrops no)
	)
	(paper "A4")
	(title_block
		(title "04192023_DAF0TMB3IC0_F0TG_MB_C_brd_V02_OCP.brd")
		(comment 1 "Grand Teton / footprints 2813-2815 of 8354")
	)
	(layers
		(0 "F.Cu" signal "TOP")
		(4 "In1.Cu" signal "GND")
		(6 "In2.Cu" signal "IN1")
		(8 "In3.Cu" signal "GND1")
		(10 "In4.Cu" signal "IN2")
		(12 "In5.Cu" signal "GND2")
		(14 "In6.Cu" signal "IN3")
		(16 "In7.Cu" signal "GND3")
		(18 "In8.Cu" signal "VCC")
		(20 "In9.Cu" signal "VCC1")
		(22 "In10.Cu" signal "GND4")
		(24 "In11.Cu" signal "IN4")
		(26 "In12.Cu" signal "GND5")
		(28 "In13.Cu" signal "IN5")
		(30 "In14.Cu" signal "GND6")
		(32 "In15.Cu" signal "IN6")
		(34 "In16.Cu" signal "GND7")
		(2 "B.Cu" signal "BOTTOM")
		(9 "F.Adhes" user "F.Adhesive")
		(11 "B.Adhes" user "B.Adhesive")
		(13 "F.Paste" user "Package Geometry/Pastemask Top")
		(15 "B.Paste" user "Package Geometry/Pastemask Bottom")
		(5 "F.SilkS" user "Ref Des/Silkscreen Top")
		(7 "B.SilkS" user "Ref Des/Silkscreen Bottom")
		(1 "F.Mask" user "Board Geometry/Soldermask Top")
		(3 "B.Mask" user "Board Geometry/Soldermask Bottom")
		(17 "Dwgs.User" user "User.Drawings")
		(19 "Cmts.User" user "User.Comments")
		(21 "Eco1.User" user "User.Eco1")
		(23 "Eco2.User" user "User.Eco2")
		(25 "Edge.Cuts" user "Board Geometry/Outline")
		(27 "Margin" user)
		(31 "F.CrtYd" user "Package Geometry/Place Bound Top")
		(29 "B.CrtYd" user "Package Geometry/Place Bound Bottom")
		(35 "F.Fab" user "Ref Des/Assembly Top")
		(33 "B.Fab" user "Ref Des/Assembly Bottom")
	)
	(footprint ""
		(layer "F.Cu")
		(at 152.018492 -117.944646 180)
		(property "Reference" "C1561"
			(at 0 0 180)
			(layer "F.SilkS")
			(hide yes)
			(effects
				(font
					(size 1.27 1.27)
				)
			)
		)
		(property "Value" ""
			(at 0 0 180)
			(layer "F.Fab")
			(effects
				(font
					(size 1.27 1.27)
				)
			)
		)
		(duplicate_pad_numbers_are_jumpers no)
		(fp_line
			(start 0.7874 0.4064)
			(end -0.7874 0.4064)
			(stroke
				(width 0.1524)
				(type default)
			)
			(layer "F.SilkS")
		)
		(fp_line
			(start 0.7874 -0.4064)
			(end 0.7874 0.4064)
			(stroke
				(width 0.1524)
				(type default)
			)
			(layer "F.SilkS")
		)
		(fp_line
			(start -0.7874 0.4064)
			(end -0.7874 -0.4064)
			(stroke
				(width 0.1524)
				(type default)
			)
			(layer "F.SilkS")
		)
		(fp_line
			(start -0.7874 -0.4064)
			(end 0.7874 -0.4064)
			(stroke
				(width 0.1524)
				(type default)
			)
			(layer "F.SilkS")
		)
		(fp_line
			(start 0.67945 0.3048)
			(end 0.120396 0.3048)
			(stroke
				(width 0.1)
				(type default)
			)
			(layer "F.Fab")
		)
		(fp_line
			(start 0.67945 -0.3048)
			(end 0.67945 0.3048)
			(stroke
				(width 0.1)
				(type default)
			)
			(layer "F.Fab")
		)
		(fp_line
			(start 0.12065 -0.2794)
			(end 0.12065 -0.3048)
			(stroke
				(width 0.1)
				(type default)
			)
			(layer "F.Fab")
		)
		(fp_line
			(start 0.12065 -0.3048)
			(end 0.67945 -0.3048)
			(stroke
				(width 0.1)
				(type default)
			)
			(layer "F.Fab")
		)
		(fp_line
			(start 0.120396 0.3048)
			(end 0.120396 0.2794)
			(stroke
				(width 0.1)
				(type default)
			)
			(layer "F.Fab")
		)
		(fp_line
			(start 0.120396 0.2794)
			(end -0.12065 0.2794)
			(stroke
				(width 0.1)
				(type default)
			)
			(layer "F.Fab")
		)
		(fp_line
			(start -0.12065 0.3048)
			(end -0.67945 0.3048)
			(stroke
				(width 0.1)
				(type default)
			)
			(layer "F.Fab")
		)
		(fp_line
			(start -0.12065 0.2794)
			(end -0.12065 0.3048)
			(stroke
				(width 0.1)
				(type default)
			)
			(layer "F.Fab")
		)
		(fp_line
			(start -0.12065 -0.2794)
			(end 0.12065 -0.2794)
			(stroke
				(width 0.1)
				(type default)
			)
			(layer "F.Fab")
		)
		(fp_line
			(start -0.12065 -0.305054)
			(end -0.12065 -0.2794)
			(stroke
				(width 0.1)
				(type default)
			)
			(layer "F.Fab")
		)
		(fp_line
			(start -0.67945 0.3048)
			(end -0.67945 -0.305054)
			(stroke
				(width 0.1)
				(type default)
			)
			(layer "F.Fab")
		)
		(fp_line
			(start -0.67945 -0.305054)
			(end -0.12065 -0.305054)
			(stroke
				(width 0.1)
				(type default)
			)
			(layer "F.Fab")
		)
		(pad "1" smd circle
			(at -0.40005 0 180)
			(size 0 0)
			(layers "F.Cu" "F.Mask" "F.Paste")
			(net "U206_VS")
		)
		(pad "2" smd circle
			(at 0.40005 0 180)
			(size 0 0)
			(layers "F.Cu" "F.Mask" "F.Paste")
			(net "GND")
		)
	)
	(footprint ""
		(layer "F.Cu")
		(at 77.215746 -394.166852 -90)
		(property "Reference" "R752"
			(at 0 0 270)
			(layer "F.SilkS")
			(hide yes)
			(effects
				(font
					(size 1.27 1.27)
				)
			)
		)
		(property "Value" ""
			(at 0 0 270)
			(layer "F.Fab")
			(effects
				(font
					(size 1.27 1.27)
				)
			)
		)
		(duplicate_pad_numbers_are_jumpers no)
		(fp_line
			(start -0.32512 0.175006)
			(end -0.32512 -0.175006)
			(stroke
				(width 0.1)
				(type default)
			)
			(layer "F.Fab")
		)
		(fp_line
			(start 0.32512 0.175006)
			(end -0.32512 0.175006)
			(stroke
				(width 0.1)
				(type default)
			)
			(layer "F.Fab")
		)
		(fp_line
			(start -0.32512 -0.175006)
			(end 0.32512 -0.175006)
			(stroke
				(width 0.1)
				(type default)
			)
			(layer "F.Fab")
		)
		(fp_line
			(start 0.32512 -0.175006)
			(end 0.32512 0.175006)
			(stroke
				(width 0.1)
				(type default)
			)
			(layer "F.Fab")
		)
		(pad "1" smd rect
			(at -0.2667 0 270)
			(size 0.3048 0.381)
			(layers "F.Cu" "F.Mask" "F.Paste")
			(net "RST_RT_CPU1_P1_RESET_R_N")
		)
		(pad "2" smd rect
			(at 0.2667 0 90)
			(size 0.3048 0.381)
			(layers "F.Cu" "F.Mask" "F.Paste")
			(net "GND")
		)
	)
	(footprint ""
		(layer "F.Cu")
		(at 250.55957 -68.946522)
		(property "Reference" "R4063"
			(at 0 0 0)
			(layer "F.SilkS")
			(hide yes)
			(effects
				(font
					(size 1.27 1.27)
				)
			)
		)
		(property "Value" ""
			(at 0 0 0)
			(layer "F.Fab")
			(effects
				(font
					(size 1.27 1.27)
				)
			)
		)
		(duplicate_pad_numbers_are_jumpers no)
		(fp_line
			(start -0.7874 -0.4064)
			(end 0.7874 -0.4064)
			(stroke
				(width 0.1524)
				(type default)
			)
			(layer "F.SilkS")
		)
		(fp_line
			(start -0.7874 0.4064)
			(end -0.7874 -0.4064)
			(stroke
				(width 0.1524)
				(type default)
			)
			(layer "F.SilkS")
		)
		(fp_line
			(start 0.7874 -0.4064)
			(end 0.7874 0.4064)
			(stroke
				(width 0.1524)
				(type default)
			)
			(layer "F.SilkS")
		)
		(fp_line
			(start 0.7874 0.4064)
			(end -0.7874 0.4064)
			(stroke
				(width 0.1524)
				(type default)
			)
			(layer "F.SilkS")
		)
		(fp_line
			(start -0.67945 -0.305054)
			(end -0.12065 -0.305054)
			(stroke
				(width 0.1)
				(type default)
			)
			(layer "F.Fab")
		)
		(fp_line
			(start -0.67945 0.3048)
			(end -0.67945 -0.305054)
			(stroke
				(width 0.1)
				(type default)
			)
			(layer "F.Fab")
		)
		(fp_line
			(start -0.12065 -0.305054)
			(end -0.12065 -0.2794)
			(stroke
				(width 0.1)
				(type default)
			)
			(layer "F.Fab")
		)
		(fp_line
			(start -0.12065 -0.2794)
			(end 0.12065 -0.2794)
			(stroke
				(width 0.1)
				(type default)
			)
			(layer "F.Fab")
		)
		(fp_line
			(start -0.12065 0.2794)
			(end -0.12065 0.3048)
			(stroke
				(width 0.1)
				(type default)
			)
			(layer "F.Fab")
		)
		(fp_line
			(start -0.12065 0.3048)
			(end -0.67945 0.3048)
			(stroke
				(width 0.1)
				(type default)
			)
			(layer "F.Fab")
		)
		(fp_line
			(start 0.120396 0.2794)
			(end -0.12065 0.2794)
			(stroke
				(width 0.1)
				(type default)
			)
			(layer "F.Fab")
		)
		(fp_line
			(start 0.120396 0.3048)
			(end 0.120396 0.2794)
			(stroke
				(width 0.1)
				(type default)
			)
			(layer "F.Fab")
		)
		(fp_line
			(start 0.12065 -0.3048)
			(end 0.67945 -0.3048)
			(stroke
				(width 0.1)
				(type default)
			)
			(layer "F.Fab")
		)
		(fp_line
			(start 0.12065 -0.2794)
			(end 0.12065 -0.3048)
			(stroke
				(width 0.1)
				(type default)
			)
			(layer "F.Fab")
		)
		(fp_line
			(start 0.67945 -0.3048)
			(end 0.67945 0.3048)
			(stroke
				(width 0.1)
				(type default)
			)
			(layer "F.Fab")
		)
		(fp_line
			(start 0.67945 0.3048)
			(end 0.120396 0.3048)
			(stroke
				(width 0.1)
				(type default)
			)
			(layer "F.Fab")
		)
		(pad "1" smd circle
			(at -0.40005 0)
			(size 0 0)
			(layers "F.Cu" "F.Mask" "F.Paste")
			(net "E1S_0_P3V3_EN")
		)
		(pad "2" smd circle
			(at 0.40005 0)
			(size 0 0)
			(layers "F.Cu" "F.Mask" "F.Paste")
			(net "P3V3_E1S_EN_0_R")
		)
	)
)
